(kicad_pcb
	(version 20260206)
	(generator "pcbnew")
	(generator_version "10.0")
	(general
		(thickness 1.6)
		(legacy_teardrops no)
	)
	(paper "A4")
	(title_block
		(title "04192023_DAF0TMB3IC0_F0TG_MB_C_brd_V02_OCP.brd")
		(comment 1 "Grand Teton / footprints 6676-6682 of 8354")
	)
	(layers
		(0 "F.Cu" signal "TOP")
		(4 "In1.Cu" signal "GND")
		(6 "In2.Cu" signal "IN1")
		(8 "In3.Cu" signal "GND1")
		(10 "In4.Cu" signal "IN2")
		(12 "In5.Cu" signal "GND2")
		(14 "In6.Cu" signal "IN3")
		(16 "In7.Cu" signal "GND3")
		(18 "In8.Cu" signal "VCC")
		(20 "In9.Cu" signal "VCC1")
		(22 "In10.Cu" signal "GND4")
		(24 "In11.Cu" signal "IN4")
		(26 "In12.Cu" signal "GND5")
		(28 "In13.Cu" signal "IN5")
		(30 "In14.Cu" signal "GND6")
		(32 "In15.Cu" signal "IN6")
		(34 "In16.Cu" signal "GND7")
		(2 "B.Cu" signal "BOTTOM")
		(9 "F.Adhes" user "F.Adhesive")
		(11 "B.Adhes" user "B.Adhesive")
		(13 "F.Paste" user "Package Geometry/Pastemask Top")
		(15 "B.Paste" user "Package Geometry/Pastemask Bottom")
		(5 "F.SilkS" user "Ref Des/Silkscreen Top")
		(7 "B.SilkS" user "Ref Des/Silkscreen Bottom")
		(1 "F.Mask" user "Board Geometry/Soldermask Top")
		(3 "B.Mask" user "Board Geometry/Soldermask Bottom")
		(17 "Dwgs.User" user "User.Drawings")
		(19 "Cmts.User" user "User.Comments")
		(21 "Eco1.User" user "User.Eco1")
		(23 "Eco2.User" user "User.Eco2")
		(25 "Edge.Cuts" user "Board Geometry/Outline")
		(27 "Margin" user)
		(31 "F.CrtYd" user "Package Geometry/Place Bound Top")
		(29 "B.CrtYd" user "Package Geometry/Place Bound Bottom")
		(35 "F.Fab" user "Ref Des/Assembly Top")
		(33 "B.Fab" user "Ref Des/Assembly Bottom")
	)
	(footprint ""
		(layer "B.Cu")
		(at 136.040114 -34.850578)
		(property "Reference" "C6039"
			(at 0 0 0)
			(layer "B.SilkS")
			(hide yes)
			(effects
				(font
					(size 1.27 1.27)
				)
				(justify mirror)
			)
		)
		(property "Value" ""
			(at 0 0 0)
			(layer "B.Fab")
			(effects
				(font
					(size 1.27 1.27)
				)
				(justify mirror)
			)
		)
		(duplicate_pad_numbers_are_jumpers no)
		(fp_line
			(start -0.7874 -0.4064)
			(end -0.7874 0.4064)
			(stroke
				(width 0.1524)
				(type default)
			)
			(layer "B.SilkS")
		)
		(fp_line
			(start -0.7874 0.4064)
			(end 0.7874 0.4064)
			(stroke
				(width 0.1524)
				(type default)
			)
			(layer "B.SilkS")
		)
		(fp_line
			(start 0.7874 -0.4064)
			(end -0.7874 -0.4064)
			(stroke
				(width 0.1524)
				(type default)
			)
			(layer "B.SilkS")
		)
		(fp_line
			(start 0.7874 0.4064)
			(end 0.7874 -0.4064)
			(stroke
				(width 0.1524)
				(type default)
			)
			(layer "B.SilkS")
		)
		(fp_line
			(start -0.67945 -0.3048)
			(end -0.67945 0.3048)
			(stroke
				(width 0.1)
				(type default)
			)
			(layer "B.Fab")
		)
		(fp_line
			(start -0.67945 0.3048)
			(end -0.120396 0.3048)
			(stroke
				(width 0.1)
				(type default)
			)
			(layer "B.Fab")
		)
		(fp_line
			(start -0.12065 -0.3048)
			(end -0.67945 -0.3048)
			(stroke
				(width 0.1)
				(type default)
			)
			(layer "B.Fab")
		)
		(fp_line
			(start -0.12065 -0.2794)
			(end -0.12065 -0.3048)
			(stroke
				(width 0.1)
				(type default)
			)
			(layer "B.Fab")
		)
		(fp_line
			(start -0.120396 0.2794)
			(end 0.12065 0.2794)
			(stroke
				(width 0.1)
				(type default)
			)
			(layer "B.Fab")
		)
		(fp_line
			(start -0.120396 0.3048)
			(end -0.120396 0.2794)
			(stroke
				(width 0.1)
				(type default)
			)
			(layer "B.Fab")
		)
		(fp_line
			(start 0.12065 -0.305054)
			(end 0.12065 -0.2794)
			(stroke
				(width 0.1)
				(type default)
			)
			(layer "B.Fab")
		)
		(fp_line
			(start 0.12065 -0.2794)
			(end -0.12065 -0.2794)
			(stroke
				(width 0.1)
				(type default)
			)
			(layer "B.Fab")
		)
		(fp_line
			(start 0.12065 0.2794)
			(end 0.12065 0.3048)
			(stroke
				(width 0.1)
				(type default)
			)
			(layer "B.Fab")
		)
		(fp_line
			(start 0.12065 0.3048)
			(end 0.67945 0.3048)
			(stroke
				(width 0.1)
				(type default)
			)
			(layer "B.Fab")
		)
		(fp_line
			(start 0.67945 -0.305054)
			(end 0.12065 -0.305054)
			(stroke
				(width 0.1)
				(type default)
			)
			(layer "B.Fab")
		)
		(fp_line
			(start 0.67945 0.3048)
			(end 0.67945 -0.305054)
			(stroke
				(width 0.1)
				(type default)
			)
			(layer "B.Fab")
		)
		(pad "1" smd circle
			(at 0.40005 0 180)
			(size 0 0)
			(layers "B.Cu" "B.Mask" "B.Paste")
			(net "P1V2_CPU0_USB_DVDD12")
		)
		(pad "2" smd circle
			(at -0.40005 0 180)
			(size 0 0)
			(layers "B.Cu" "B.Mask" "B.Paste")
			(net "GND")
		)
	)
	(footprint ""
		(layer "B.Cu")
		(at 411.470856 -163.891468 -90)
		(property "Reference" "PC610_3"
			(at 0 0 90)
			(layer "B.SilkS")
			(hide yes)
			(effects
				(font
					(size 1.27 1.27)
				)
				(justify mirror)
			)
		)
		(property "Value" ""
			(at 0 0 90)
			(layer "B.Fab")
			(effects
				(font
					(size 1.27 1.27)
				)
				(justify mirror)
			)
		)
		(duplicate_pad_numbers_are_jumpers no)
		(fp_line
			(start -1.524 0.762)
			(end 1.524 0.762)
			(stroke
				(width 0.1524)
				(type default)
			)
			(layer "B.SilkS")
		)
		(fp_line
			(start 1.524 0.762)
			(end 1.524 -0.762)
			(stroke
				(width 0.1524)
				(type default)
			)
			(layer "B.SilkS")
		)
		(fp_line
			(start -1.524 -0.762)
			(end -1.524 0.762)
			(stroke
				(width 0.1524)
				(type default)
			)
			(layer "B.SilkS")
		)
		(fp_line
			(start 1.524 -0.762)
			(end -1.524 -0.762)
			(stroke
				(width 0.1524)
				(type default)
			)
			(layer "B.SilkS")
		)
		(fp_line
			(start -1.1049 0.724916)
			(end -1.1049 -0.724916)
			(stroke
				(width 0.1)
				(type default)
			)
			(layer "B.Fab")
		)
		(fp_line
			(start 1.1049 0.724916)
			(end -1.1049 0.724916)
			(stroke
				(width 0.1)
				(type default)
			)
			(layer "B.Fab")
		)
		(fp_line
			(start -1.1049 -0.724916)
			(end 1.1049 -0.724916)
			(stroke
				(width 0.1)
				(type default)
			)
			(layer "B.Fab")
		)
		(fp_line
			(start 1.1049 -0.724916)
			(end 1.1049 0.724916)
			(stroke
				(width 0.1)
				(type default)
			)
			(layer "B.Fab")
		)
		(pad "1" smd rect
			(at 0.889 0 270)
			(size 1.016 1.27)
			(layers "B.Cu" "B.Mask" "B.Paste")
			(net "SW_P12V_AUX_PVDDCR_SOC_P0_FLT")
		)
		(pad "2" smd rect
			(at -0.889 0 270)
			(size 1.016 1.27)
			(layers "B.Cu" "B.Mask" "B.Paste")
			(net "GND")
		)
	)
	(footprint ""
		(layer "B.Cu")
		(at 188.712094 -116.242846)
		(property "Reference" "C360"
			(at 0 0 0)
			(layer "B.SilkS")
			(hide yes)
			(effects
				(font
					(size 1.27 1.27)
				)
				(justify mirror)
			)
		)
		(property "Value" ""
			(at 0 0 0)
			(layer "B.Fab")
			(effects
				(font
					(size 1.27 1.27)
				)
				(justify mirror)
			)
		)
		(duplicate_pad_numbers_are_jumpers no)
		(fp_line
			(start -0.69215 -0.2921)
			(end -0.69215 0.2921)
			(stroke
				(width 0.1524)
				(type default)
			)
			(layer "B.SilkS")
		)
		(fp_line
			(start -0.69215 0.2921)
			(end 0.69215 0.2921)
			(stroke
				(width 0.1524)
				(type default)
			)
			(layer "B.SilkS")
		)
		(fp_line
			(start 0.69215 -0.2921)
			(end -0.69215 -0.2921)
			(stroke
				(width 0.1524)
				(type default)
			)
			(layer "B.SilkS")
		)
		(fp_line
			(start 0.69215 0.2921)
			(end 0.69215 -0.2921)
			(stroke
				(width 0.1524)
				(type default)
			)
			(layer "B.SilkS")
		)
		(fp_line
			(start -0.51435 -0.2794)
			(end -0.51435 0.2794)
			(stroke
				(width 0.1)
				(type default)
			)
			(layer "B.Fab")
		)
		(fp_line
			(start -0.51435 0.2794)
			(end 0.51435 0.2794)
			(stroke
				(width 0.1)
				(type default)
			)
			(layer "B.Fab")
		)
		(fp_line
			(start 0.51435 -0.2794)
			(end -0.51435 -0.2794)
			(stroke
				(width 0.1)
				(type default)
			)
			(layer "B.Fab")
		)
		(fp_line
			(start 0.51435 0.2794)
			(end 0.51435 -0.2794)
			(stroke
				(width 0.1)
				(type default)
			)
			(layer "B.Fab")
		)
		(pad "1" smd circle
			(at 0.40005 0 180)
			(size 0 0)
			(layers "B.Cu" "B.Mask" "B.Paste")
			(net "P3V3_AUX")
		)
		(pad "2" smd circle
			(at -0.40005 0 180)
			(size 0 0)
			(layers "B.Cu" "B.Mask" "B.Paste")
			(net "GND")
		)
		(zone
			(layer "B.Cu")
			(hatch none 0.5)
			(connect_pads
				(clearance 0)
			)
			(min_thickness 0.25)
			(keepout
				(tracks not_allowed)
				(vias allowed)
				(pads allowed)
				(copperpour not_allowed)
				(footprints allowed)
			)
			(placement
				(enabled no)
				(sheetname "")
			)
			(fill
				(thermal_gap 0.5)
				(thermal_bridge_width 0.5)
				(island_removal_mode 0)
			)
			(polygon
				(pts
					(xy 188.521594 -116.155216) (xy 188.521594 -116.330476) (xy 188.611764 -116.388896) (xy 188.811154 -116.388896)
					(xy 188.902594 -116.33073) (xy 188.902594 -116.155216) (xy 188.811154 -116.09705) (xy 188.611764 -116.09705)
				)
			)
		)
	)
	(footprint ""
		(layer "B.Cu")
		(at 362.051346 -249.36831)
		(property "Reference" "C2175"
			(at 0 0 0)
			(layer "B.SilkS")
			(hide yes)
			(effects
				(font
					(size 1.27 1.27)
				)
				(justify mirror)
			)
		)
		(property "Value" ""
			(at 0 0 0)
			(layer "B.Fab")
			(effects
				(font
					(size 1.27 1.27)
				)
				(justify mirror)
			)
		)
		(duplicate_pad_numbers_are_jumpers no)
		(fp_line
			(start -0.7874 -0.4064)
			(end -0.7874 0.4064)
			(stroke
				(width 0.1524)
				(type default)
			)
			(layer "B.SilkS")
		)
		(fp_line
			(start -0.7874 0.4064)
			(end 0.7874 0.4064)
			(stroke
				(width 0.1524)
				(type default)
			)
			(layer "B.SilkS")
		)
		(fp_line
			(start 0.7874 -0.4064)
			(end -0.7874 -0.4064)
			(stroke
				(width 0.1524)
				(type default)
			)
			(layer "B.SilkS")
		)
		(fp_line
			(start 0.7874 0.4064)
			(end 0.7874 -0.4064)
			(stroke
				(width 0.1524)
				(type default)
			)
			(layer "B.SilkS")
		)
		(fp_line
			(start -0.67945 -0.3048)
			(end -0.67945 0.3048)
			(stroke
				(width 0.1)
				(type default)
			)
			(layer "B.Fab")
		)
		(fp_line
			(start -0.67945 0.3048)
			(end -0.120396 0.3048)
			(stroke
				(width 0.1)
				(type default)
			)
			(layer "B.Fab")
		)
		(fp_line
			(start -0.12065 -0.3048)
			(end -0.67945 -0.3048)
			(stroke
				(width 0.1)
				(type default)
			)
			(layer "B.Fab")
		)
		(fp_line
			(start -0.12065 -0.2794)
			(end -0.12065 -0.3048)
			(stroke
				(width 0.1)
				(type default)
			)
			(layer "B.Fab")
		)
		(fp_line
			(start -0.120396 0.2794)
			(end 0.12065 0.2794)
			(stroke
				(width 0.1)
				(type default)
			)
			(layer "B.Fab")
		)
		(fp_line
			(start -0.120396 0.3048)
			(end -0.120396 0.2794)
			(stroke
				(width 0.1)
				(type default)
			)
			(layer "B.Fab")
		)
		(fp_line
			(start 0.12065 -0.305054)
			(end 0.12065 -0.2794)
			(stroke
				(width 0.1)
				(type default)
			)
			(layer "B.Fab")
		)
		(fp_line
			(start 0.12065 -0.2794)
			(end -0.12065 -0.2794)
			(stroke
				(width 0.1)
				(type default)
			)
			(layer "B.Fab")
		)
		(fp_line
			(start 0.12065 0.2794)
			(end 0.12065 0.3048)
			(stroke
				(width 0.1)
				(type default)
			)
			(layer "B.Fab")
		)
		(fp_line
			(start 0.12065 0.3048)
			(end 0.67945 0.3048)
			(stroke
				(width 0.1)
				(type default)
			)
			(layer "B.Fab")
		)
		(fp_line
			(start 0.67945 -0.305054)
			(end 0.12065 -0.305054)
			(stroke
				(width 0.1)
				(type default)
			)
			(layer "B.Fab")
		)
		(fp_line
			(start 0.67945 0.3048)
			(end 0.67945 -0.305054)
			(stroke
				(width 0.1)
				(type default)
			)
			(layer "B.Fab")
		)
		(pad "1" smd circle
			(at 0.40005 0 180)
			(size 0 0)
			(layers "B.Cu" "B.Mask" "B.Paste")
			(net "PVDDCR_CPU0_P0")
		)
		(pad "2" smd circle
			(at -0.40005 0 180)
			(size 0 0)
			(layers "B.Cu" "B.Mask" "B.Paste")
			(net "GND")
		)
	)
	(footprint ""
		(layer "B.Cu")
		(at 450.666866 -397.91767 -90)
		(property "Reference" "PR6560"
			(at 0 0 90)
			(layer "B.SilkS")
			(hide yes)
			(effects
				(font
					(size 1.27 1.27)
				)
				(justify mirror)
			)
		)
		(property "Value" ""
			(at 0 0 90)
			(layer "B.Fab")
			(effects
				(font
					(size 1.27 1.27)
				)
				(justify mirror)
			)
		)
		(duplicate_pad_numbers_are_jumpers no)
		(fp_line
			(start -0.7874 0.4064)
			(end 0.7874 0.4064)
			(stroke
				(width 0.1524)
				(type default)
			)
			(layer "B.SilkS")
		)
		(fp_line
			(start 0.7874 0.4064)
			(end 0.7874 -0.4064)
			(stroke
				(width 0.1524)
				(type default)
			)
			(layer "B.SilkS")
		)
		(fp_line
			(start -0.7874 -0.4064)
			(end -0.7874 0.4064)
			(stroke
				(width 0.1524)
				(type default)
			)
			(layer "B.SilkS")
		)
		(fp_line
			(start 0.7874 -0.4064)
			(end -0.7874 -0.4064)
			(stroke
				(width 0.1524)
				(type default)
			)
			(layer "B.SilkS")
		)
		(fp_line
			(start -0.67945 0.3048)
			(end -0.120396 0.3048)
			(stroke
				(width 0.1)
				(type default)
			)
			(layer "B.Fab")
		)
		(fp_line
			(start -0.120396 0.3048)
			(end -0.120396 0.2794)
			(stroke
				(width 0.1)
				(type default)
			)
			(layer "B.Fab")
		)
		(fp_line
			(start 0.12065 0.3048)
			(end 0.67945 0.3048)
			(stroke
				(width 0.1)
				(type default)
			)
			(layer "B.Fab")
		)
		(fp_line
			(start 0.67945 0.3048)
			(end 0.67945 -0.305054)
			(stroke
				(width 0.1)
				(type default)
			)
			(layer "B.Fab")
		)
		(fp_line
			(start -0.120396 0.2794)
			(end 0.12065 0.2794)
			(stroke
				(width 0.1)
				(type default)
			)
			(layer "B.Fab")
		)
		(fp_line
			(start 0.12065 0.2794)
			(end 0.12065 0.3048)
			(stroke
				(width 0.1)
				(type default)
			)
			(layer "B.Fab")
		)
		(fp_line
			(start -0.12065 -0.2794)
			(end -0.12065 -0.3048)
			(stroke
				(width 0.1)
				(type default)
			)
			(layer "B.Fab")
		)
		(fp_line
			(start 0.12065 -0.2794)
			(end -0.12065 -0.2794)
			(stroke
				(width 0.1)
				(type default)
			)
			(layer "B.Fab")
		)
		(fp_line
			(start -0.67945 -0.3048)
			(end -0.67945 0.3048)
			(stroke
				(width 0.1)
				(type default)
			)
			(layer "B.Fab")
		)
		(fp_line
			(start -0.12065 -0.3048)
			(end -0.67945 -0.3048)
			(stroke
				(width 0.1)
				(type default)
			)
			(layer "B.Fab")
		)
		(fp_line
			(start 0.12065 -0.305054)
			(end 0.12065 -0.2794)
			(stroke
				(width 0.1)
				(type default)
			)
			(layer "B.Fab")
		)
		(fp_line
			(start 0.67945 -0.305054)
			(end 0.12065 -0.305054)
			(stroke
				(width 0.1)
				(type default)
			)
			(layer "B.Fab")
		)
		(pad "1" smd circle
			(at 0.40005 0 90)
			(size 0 0)
			(layers "B.Cu" "B.Mask" "B.Paste")
			(net "P0V9_RETIMER_CPU0_PVCC")
		)
		(pad "2" smd circle
			(at -0.40005 0 90)
			(size 0 0)
			(layers "B.Cu" "B.Mask" "B.Paste")
			(net "P0V9_RETIMER_CPU0_VCC2")
		)
	)
	(footprint ""
		(layer "B.Cu")
		(at 51.72964 -426.003212 -90)
		(property "Reference" "R3513"
			(at 0 0 90)
			(layer "B.SilkS")
			(hide yes)
			(effects
				(font
					(size 1.27 1.27)
				)
				(justify mirror)
			)
		)
		(property "Value" ""
			(at 0 0 90)
			(layer "B.Fab")
			(effects
				(font
					(size 1.27 1.27)
				)
				(justify mirror)
			)
		)
		(duplicate_pad_numbers_are_jumpers no)
		(fp_line
			(start -0.7874 0.4064)
			(end 0.7874 0.4064)
			(stroke
				(width 0.1524)
				(type default)
			)
			(layer "B.SilkS")
		)
		(fp_line
			(start 0.7874 0.4064)
			(end 0.7874 -0.4064)
			(stroke
				(width 0.1524)
				(type default)
			)
			(layer "B.SilkS")
		)
		(fp_line
			(start -0.7874 -0.4064)
			(end -0.7874 0.4064)
			(stroke
				(width 0.1524)
				(type default)
			)
			(layer "B.SilkS")
		)
		(fp_line
			(start 0.7874 -0.4064)
			(end -0.7874 -0.4064)
			(stroke
				(width 0.1524)
				(type default)
			)
			(layer "B.SilkS")
		)
		(fp_line
			(start -0.67945 0.3048)
			(end -0.120396 0.3048)
			(stroke
				(width 0.1)
				(type default)
			)
			(layer "B.Fab")
		)
		(fp_line
			(start -0.120396 0.3048)
			(end -0.120396 0.2794)
			(stroke
				(width 0.1)
				(type default)
			)
			(layer "B.Fab")
		)
		(fp_line
			(start 0.12065 0.3048)
			(end 0.67945 0.3048)
			(stroke
				(width 0.1)
				(type default)
			)
			(layer "B.Fab")
		)
		(fp_line
			(start 0.67945 0.3048)
			(end 0.67945 -0.305054)
			(stroke
				(width 0.1)
				(type default)
			)
			(layer "B.Fab")
		)
		(fp_line
			(start -0.120396 0.2794)
			(end 0.12065 0.2794)
			(stroke
				(width 0.1)
				(type default)
			)
			(layer "B.Fab")
		)
		(fp_line
			(start 0.12065 0.2794)
			(end 0.12065 0.3048)
			(stroke
				(width 0.1)
				(type default)
			)
			(layer "B.Fab")
		)
		(fp_line
			(start -0.12065 -0.2794)
			(end -0.12065 -0.3048)
			(stroke
				(width 0.1)
				(type default)
			)
			(layer "B.Fab")
		)
		(fp_line
			(start 0.12065 -0.2794)
			(end -0.12065 -0.2794)
			(stroke
				(width 0.1)
				(type default)
			)
			(layer "B.Fab")
		)
		(fp_line
			(start -0.67945 -0.3048)
			(end -0.67945 0.3048)
			(stroke
				(width 0.1)
				(type default)
			)
			(layer "B.Fab")
		)
		(fp_line
			(start -0.12065 -0.3048)
			(end -0.67945 -0.3048)
			(stroke
				(width 0.1)
				(type default)
			)
			(layer "B.Fab")
		)
		(fp_line
			(start 0.12065 -0.305054)
			(end 0.12065 -0.2794)
			(stroke
				(width 0.1)
				(type default)
			)
			(layer "B.Fab")
		)
		(fp_line
			(start 0.67945 -0.305054)
			(end 0.12065 -0.305054)
			(stroke
				(width 0.1)
				(type default)
			)
			(layer "B.Fab")
		)
		(pad "1" smd circle
			(at 0.40005 0 90)
			(size 0 0)
			(layers "B.Cu" "B.Mask" "B.Paste")
			(net "FM_GPU_PWRGD")
		)
		(pad "2" smd circle
			(at -0.40005 0 90)
			(size 0 0)
			(layers "B.Cu" "B.Mask" "B.Paste")
			(net "GND")
		)
	)
	(footprint ""
		(layer "B.Cu")
		(at 48.71847 -388.011162 -90)
		(property "Reference" "C141"
			(at 0 0 90)
			(layer "B.SilkS")
			(hide yes)
			(effects
				(font
					(size 1.27 1.27)
				)
				(justify mirror)
			)
		)
		(property "Value" ""
			(at 0 0 90)
			(layer "B.Fab")
			(effects
				(font
					(size 1.27 1.27)
				)
				(justify mirror)
			)
		)
		(duplicate_pad_numbers_are_jumpers no)
		(fp_line
			(start -0.299974 0.150114)
			(end 0.299974 0.150114)
			(stroke
				(width 0.1)
				(type default)
			)
			(layer "B.Fab")
		)
		(fp_line
			(start 0.299974 0.150114)
			(end 0.299974 -0.150114)
			(stroke
				(width 0.1)
				(type default)
			)
			(layer "B.Fab")
		)
		(fp_line
			(start -0.299974 -0.150114)
			(end -0.299974 0.150114)
			(stroke
				(width 0.1)
				(type default)
			)
			(layer "B.Fab")
		)
		(fp_line
			(start 0.299974 -0.150114)
			(end -0.299974 -0.150114)
			(stroke
				(width 0.1)
				(type default)
			)
			(layer "B.Fab")
		)
		(pad "1" smd rect
			(at 0.2667 0 90)
			(size 0.3048 0.381)
			(layers "B.Cu" "B.Mask" "B.Paste")
			(net "P0V9_CPU1_RT0_2A")
		)
		(pad "2" smd rect
			(at -0.2667 0 90)
			(size 0.3048 0.381)
			(layers "B.Cu" "B.Mask" "B.Paste")
			(net "GND")
		)
	)
)
